(kicad_pcb
	(version 20260206)
	(generator "pcbnew")
	(generator_version "10.0")
	(general
		(thickness 1.6)
		(legacy_teardrops no)
	)
	(paper "A4")
	(title_block
		(title "panther-plus-userver — 13130-1b_20150205.brd")
		(comment 1 "Honey Badger (Wiwynn) / footprints 759-765 of 1509")
	)
	(layers
		(0 "F.Cu" signal "TOP")
		(4 "In1.Cu" signal "L2")
		(6 "In2.Cu" signal "L3")
		(8 "In3.Cu" signal "L4")
		(10 "In4.Cu" signal "L5")
		(12 "In5.Cu" signal "L6")
		(14 "In6.Cu" signal "L7")
		(16 "In7.Cu" signal "L8")
		(18 "In8.Cu" signal "L9")
		(20 "In9.Cu" signal "L10")
		(22 "In10.Cu" signal "L11")
		(2 "B.Cu" signal "BOTTOM")
		(9 "F.Adhes" user "F.Adhesive")
		(11 "B.Adhes" user "B.Adhesive")
		(13 "F.Paste" user "Package Geometry/Pastemask Top")
		(15 "B.Paste" user "Package Geometry/Pastemask Bottom")
		(5 "F.SilkS" user "Ref Des/Silkscreen Top")
		(7 "B.SilkS" user "Ref Des/Silkscreen Bottom")
		(1 "F.Mask" user "Board Geometry/Soldermask Top")
		(3 "B.Mask" user "Board Geometry/Soldermask Bottom")
		(17 "Dwgs.User" user "User.Drawings")
		(19 "Cmts.User" user "User.Comments")
		(21 "Eco1.User" user "User.Eco1")
		(23 "Eco2.User" user "User.Eco2")
		(25 "Edge.Cuts" user "Board Geometry/Outline")
		(27 "Margin" user)
		(31 "F.CrtYd" user "Package Geometry/Place Bound Top")
		(29 "B.CrtYd" user "Package Geometry/Place Bound Bottom")
		(35 "F.Fab" user "Ref Des/Assembly Top")
		(33 "B.Fab" user "Ref Des/Assembly Bottom")
	)
	(footprint ""
		(layer "F.Cu")
		(at 6.096 -32.004 180)
		(property "Reference" "PR203"
			(at 0 0 180)
			(layer "F.SilkS")
			(hide yes)
			(effects
				(font
					(size 1.27 1.27)
				)
			)
		)
		(property "Value" "100KR2F-L1-GP"
			(at 1.7907 -1.1176 180)
			(unlocked yes)
			(layer "F.Fab")
			(hide yes)
			(effects
				(font
					(size 1.016 1.016)
					(thickness 0.1524)
				)
			)
		)
		(property "Device Type" "R402H16"
			(at 1.7907 -2.6416 180)
			(unlocked yes)
			(layer "F.Fab")
			(hide yes)
			(effects
				(font
					(size 1.016 1.016)
					(thickness 0.1524)
				)
			)
		)
		(duplicate_pad_numbers_are_jumpers no)
		(fp_rect
			(start -0.381 0.8382)
			(end 0.381 -0.8382)
			(stroke
				(width 0)
				(type default)
			)
			(fill no)
			(layer "F.CrtYd")
		)
		(fp_rect
			(start -0.381 0.8382)
			(end 0.381 -0.8382)
			(stroke
				(width 0)
				(type default)
			)
			(fill no)
			(layer "F.Fab")
		)
		(pad "1" smd custom
			(at 0 -0.4318 180)
			(size 0.127 0.127)
			(layers "F.Cu" "F.Mask" "F.Paste")
			(net "AGND_P3V3_STBY")
			(options
				(clearance outline)
				(anchor circle)
			)
			(primitives
				(gr_poly
					(pts
						(arc
							(start -0.2032 -0.2794)
							(mid -0.239121 -0.264521)
							(end -0.254 -0.2286)
						)
						(arc
							(start -0.254 0.2286)
							(mid -0.239121 0.264521)
							(end -0.2032 0.2794)
						)
						(arc
							(start 0.2032 0.2794)
							(mid 0.239121 0.264521)
							(end 0.254 0.2286)
						)
						(arc
							(start 0.254 -0.2286)
							(mid 0.239121 -0.264521)
							(end 0.2032 -0.2794)
						)
					)
					(width 0)
					(fill yes)
				)
			)
		)
		(pad "2" smd custom
			(at 0 0.4318 180)
			(size 0.127 0.127)
			(layers "F.Cu" "F.Mask" "F.Paste")
			(net "P3V3_STBY_MODE")
			(options
				(clearance outline)
				(anchor circle)
			)
			(primitives
				(gr_poly
					(pts
						(arc
							(start -0.2032 -0.2794)
							(mid -0.239121 -0.264521)
							(end -0.254 -0.2286)
						)
						(arc
							(start -0.254 0.2286)
							(mid -0.239121 0.264521)
							(end -0.2032 0.2794)
						)
						(arc
							(start 0.2032 0.2794)
							(mid 0.239121 0.264521)
							(end 0.254 0.2286)
						)
						(arc
							(start 0.254 -0.2286)
							(mid 0.239121 -0.264521)
							(end 0.2032 -0.2794)
						)
					)
					(width 0)
					(fill yes)
				)
			)
		)
	)
	(footprint ""
		(layer "F.Cu")
		(at 52.767992 -28.796234 -90)
		(property "Reference" "SKT1"
			(at 0 0 270)
			(layer "F.SilkS")
			(hide yes)
			(effects
				(font
					(size 1.27 1.27)
				)
			)
		)
		(property "Value" "SKT-G6179T010-001-GP"
			(at -7.4676 -8.382 270)
			(unlocked yes)
			(layer "F.Fab")
			(hide yes)
			(effects
				(font
					(size 1.016 1.016)
					(thickness 0.1524)
				)
			)
		)
		(property "Device Type" "G6179HT0321-001"
			(at -7.4676 -9.906 270)
			(unlocked yes)
			(layer "F.Fab")
			(hide yes)
			(effects
				(font
					(size 1.016 1.016)
					(thickness 0.1524)
				)
			)
		)
		(duplicate_pad_numbers_are_jumpers no)
		(fp_line
			(start -5.2832 5.6007)
			(end -5.2832 2.2479)
			(stroke
				(width 0.1524)
				(type default)
			)
			(layer "F.SilkS")
		)
		(fp_line
			(start 4.8768 5.6007)
			(end -5.2832 5.6007)
			(stroke
				(width 0.1524)
				(type default)
			)
			(layer "F.SilkS")
		)
		(fp_line
			(start -8.9662 2.2479)
			(end -8.9662 -2.2479)
			(stroke
				(width 0.1524)
				(type default)
			)
			(layer "F.SilkS")
		)
		(fp_line
			(start -5.2832 2.2479)
			(end -8.9662 2.2479)
			(stroke
				(width 0.1524)
				(type default)
			)
			(layer "F.SilkS")
		)
		(fp_line
			(start -8.9662 -2.2479)
			(end -5.2832 -2.2479)
			(stroke
				(width 0.1524)
				(type default)
			)
			(layer "F.SilkS")
		)
		(fp_line
			(start -5.2832 -2.2479)
			(end -5.2832 -5.6007)
			(stroke
				(width 0.1524)
				(type default)
			)
			(layer "F.SilkS")
		)
		(fp_line
			(start -5.2832 -5.6007)
			(end 4.8768 -5.6007)
			(stroke
				(width 0.1524)
				(type default)
			)
			(layer "F.SilkS")
		)
		(fp_line
			(start 4.8768 -5.6007)
			(end 4.8768 5.6007)
			(stroke
				(width 0.1524)
				(type default)
			)
			(layer "F.SilkS")
		)
		(fp_poly
			(pts
				(xy 1.397 -6.1849) (xy 2.413 -6.1849) (xy 1.905 -5.6769)
			)
			(stroke
				(width 0)
				(type default)
			)
			(fill yes)
			(layer "F.SilkS")
		)
		(fp_poly
			(pts
				(xy -2.2225 2.20853) (xy 2.2225 2.20853) (xy 2.2225 -2.20853) (xy -2.2225 -2.20853)
			)
			(stroke
				(width 0)
				(type default)
			)
			(fill yes)
			(layer "F.SilkS")
		)
		(fp_poly
			(pts
				(xy -5.2832 5.6007) (xy -5.2832 2.2479) (xy -8.9662 2.2479) (xy -8.9662 -2.2479) (xy -5.2832 -2.2479)
				(xy -5.2832 -5.6007) (xy 4.8768 -5.6007) (xy 4.8768 5.6007)
			)
			(stroke
				(width 0)
				(type default)
			)
			(fill no)
			(layer "F.CrtYd")
		)
		(fp_poly
			(pts
				(xy -5.2832 5.6007) (xy -5.2832 2.2479) (xy -8.9662 2.2479) (xy -8.9662 -2.2479) (xy -5.2832 -2.2479)
				(xy -5.2832 -5.6007) (xy 4.8768 -5.6007) (xy 4.8768 5.6007)
			)
			(stroke
				(width 0)
				(type default)
			)
			(fill no)
			(layer "F.Fab")
		)
		(pad "1" smd rect
			(at 1.905 -3.33883 270)
			(size 0.635 1.8542)
			(layers "F.Cu" "F.Mask" "F.Paste")
			(net "SPI_CS0_N_M_1")
		)
		(pad "2" smd rect
			(at 0.635 -3.33883 270)
			(size 0.635 1.8542)
			(layers "F.Cu" "F.Mask" "F.Paste")
			(net "SPI_MISO_R_1")
		)
		(pad "3" smd rect
			(at -0.635 -3.33883 270)
			(size 0.635 1.8542)
			(layers "F.Cu" "F.Mask" "F.Paste")
			(net "SPI_WP_R_N_1")
		)
		(pad "4" smd rect
			(at -1.905 -3.33883 270)
			(size 0.635 1.8542)
			(layers "F.Cu" "F.Mask" "F.Paste")
			(net "GND")
		)
		(pad "5" smd rect
			(at -1.905 3.33883 270)
			(size 0.635 1.8542)
			(layers "F.Cu" "F.Mask" "F.Paste")
			(net "SPI_MOSI_R_1")
		)
		(pad "6" smd rect
			(at -0.635 3.33883 270)
			(size 0.635 1.8542)
			(layers "F.Cu" "F.Mask" "F.Paste")
			(net "SPI_SCLK_R_1")
		)
		(pad "7" smd rect
			(at 0.635 3.33883 270)
			(size 0.635 1.8542)
			(layers "F.Cu" "F.Mask" "F.Paste")
			(net "SPI_HOLD#")
		)
		(pad "8" smd rect
			(at 1.905 3.33883 270)
			(size 0.635 1.8542)
			(layers "F.Cu" "F.Mask" "F.Paste")
			(net "P3V3_CPU")
		)
	)
	(footprint ""
		(layer "F.Cu")
		(at 180.594 -16.51 180)
		(property "Reference" "PR169"
			(at 0 0 180)
			(layer "F.SilkS")
			(hide yes)
			(effects
				(font
					(size 1.27 1.27)
				)
			)
		)
		(property "Value" "20KR2F-L-GP"
			(at 0.064008 -3.993896 180)
			(unlocked yes)
			(layer "F.Fab")
			(hide yes)
			(effects
				(font
					(size 1.016 1.016)
					(thickness 0.1524)
				)
			)
		)
		(property "Device Type" "R402H16"
			(at 0.064008 -5.517896 180)
			(unlocked yes)
			(layer "F.Fab")
			(hide yes)
			(effects
				(font
					(size 1.016 1.016)
					(thickness 0.1524)
				)
			)
		)
		(duplicate_pad_numbers_are_jumpers no)
		(fp_rect
			(start -0.381 0.8382)
			(end 0.381 -0.8382)
			(stroke
				(width 0)
				(type default)
			)
			(fill no)
			(layer "F.CrtYd")
		)
		(fp_rect
			(start -0.381 0.8382)
			(end 0.381 -0.8382)
			(stroke
				(width 0)
				(type default)
			)
			(fill no)
			(layer "F.Fab")
		)
		(pad "1" smd custom
			(at 0 -0.4318 180)
			(size 0.127 0.127)
			(layers "F.Cu" "F.Mask" "F.Paste")
			(net "PV_VDDR")
			(options
				(clearance outline)
				(anchor circle)
			)
			(primitives
				(gr_poly
					(pts
						(arc
							(start -0.2032 -0.2794)
							(mid -0.239121 -0.264521)
							(end -0.254 -0.2286)
						)
						(arc
							(start -0.254 0.2286)
							(mid -0.239121 0.264521)
							(end -0.2032 0.2794)
						)
						(arc
							(start 0.2032 0.2794)
							(mid 0.239121 0.264521)
							(end 0.254 0.2286)
						)
						(arc
							(start 0.254 -0.2286)
							(mid 0.239121 -0.264521)
							(end 0.2032 -0.2794)
						)
					)
					(width 0)
					(fill yes)
				)
			)
		)
		(pad "2" smd custom
			(at 0 0.4318 180)
			(size 0.127 0.127)
			(layers "F.Cu" "F.Mask" "F.Paste")
			(net "PV_VTT_DDR_B_REFIN")
			(options
				(clearance outline)
				(anchor circle)
			)
			(primitives
				(gr_poly
					(pts
						(arc
							(start -0.2032 -0.2794)
							(mid -0.239121 -0.264521)
							(end -0.254 -0.2286)
						)
						(arc
							(start -0.254 0.2286)
							(mid -0.239121 0.264521)
							(end -0.2032 0.2794)
						)
						(arc
							(start 0.2032 0.2794)
							(mid 0.239121 0.264521)
							(end 0.254 0.2286)
						)
						(arc
							(start 0.254 -0.2286)
							(mid 0.239121 -0.264521)
							(end 0.2032 -0.2794)
						)
					)
					(width 0)
					(fill yes)
				)
			)
		)
	)
	(footprint ""
		(layer "F.Cu")
		(at 53.5432 -49.276)
		(property "Reference" "PR159"
			(at 0 0 0)
			(layer "F.SilkS")
			(hide yes)
			(effects
				(font
					(size 1.27 1.27)
				)
			)
		)
		(property "Value" "10R2F-L-GP"
			(at 1.7907 -1.1176 0)
			(unlocked yes)
			(layer "F.Fab")
			(hide yes)
			(effects
				(font
					(size 1.016 1.016)
					(thickness 0.1524)
				)
			)
		)
		(property "Device Type" "R402H14"
			(at 1.7907 -2.6416 0)
			(unlocked yes)
			(layer "F.Fab")
			(hide yes)
			(effects
				(font
					(size 1.016 1.016)
					(thickness 0.1524)
				)
			)
		)
		(duplicate_pad_numbers_are_jumpers no)
		(fp_rect
			(start -0.381 0.8382)
			(end 0.381 -0.8382)
			(stroke
				(width 0)
				(type default)
			)
			(fill no)
			(layer "F.CrtYd")
		)
		(fp_rect
			(start -0.381 0.8382)
			(end 0.381 -0.8382)
			(stroke
				(width 0)
				(type default)
			)
			(fill no)
			(layer "F.Fab")
		)
		(pad "1" smd custom
			(at 0 -0.4318)
			(size 0.127 0.127)
			(layers "F.Cu" "F.Mask" "F.Paste")
			(net "VR_AVIN_P1V0_STBY")
			(options
				(clearance outline)
				(anchor circle)
			)
			(primitives
				(gr_poly
					(pts
						(arc
							(start -0.2032 -0.2794)
							(mid -0.239121 -0.264521)
							(end -0.254 -0.2286)
						)
						(arc
							(start -0.254 0.2286)
							(mid -0.239121 0.264521)
							(end -0.2032 0.2794)
						)
						(arc
							(start 0.2032 0.2794)
							(mid 0.239121 0.264521)
							(end 0.254 0.2286)
						)
						(arc
							(start 0.254 -0.2286)
							(mid 0.239121 -0.264521)
							(end 0.2032 -0.2794)
						)
					)
					(width 0)
					(fill yes)
				)
			)
		)
		(pad "2" smd custom
			(at 0 0.4318)
			(size 0.127 0.127)
			(layers "F.Cu" "F.Mask" "F.Paste")
			(net "VR_PVIN_P1V0_STBY")
			(options
				(clearance outline)
				(anchor circle)
			)
			(primitives
				(gr_poly
					(pts
						(arc
							(start -0.2032 -0.2794)
							(mid -0.239121 -0.264521)
							(end -0.254 -0.2286)
						)
						(arc
							(start -0.254 0.2286)
							(mid -0.239121 0.264521)
							(end -0.2032 0.2794)
						)
						(arc
							(start 0.2032 0.2794)
							(mid 0.239121 0.264521)
							(end 0.254 0.2286)
						)
						(arc
							(start 0.254 -0.2286)
							(mid 0.239121 -0.264521)
							(end 0.2032 -0.2794)
						)
					)
					(width 0)
					(fill yes)
				)
			)
		)
	)
	(footprint ""
		(layer "F.Cu")
		(at 70.7644 -45.3136 -90)
		(property "Reference" "R67"
			(at 0 0 270)
			(layer "F.SilkS")
			(hide yes)
			(effects
				(font
					(size 1.27 1.27)
				)
			)
		)
		(property "Value" "4K7R2F-GP"
			(at 0.064008 -3.993896 270)
			(unlocked yes)
			(layer "F.Fab")
			(hide yes)
			(effects
				(font
					(size 1.016 1.016)
					(thickness 0.1524)
				)
			)
		)
		(property "Device Type" "R402H16"
			(at 0.064008 -5.517896 270)
			(unlocked yes)
			(layer "F.Fab")
			(hide yes)
			(effects
				(font
					(size 1.016 1.016)
					(thickness 0.1524)
				)
			)
		)
		(duplicate_pad_numbers_are_jumpers no)
		(fp_rect
			(start -0.381 0.8382)
			(end 0.381 -0.8382)
			(stroke
				(width 0)
				(type default)
			)
			(fill no)
			(layer "F.CrtYd")
		)
		(fp_rect
			(start -0.381 0.8382)
			(end 0.381 -0.8382)
			(stroke
				(width 0)
				(type default)
			)
			(fill no)
			(layer "F.Fab")
		)
		(pad "1" smd custom
			(at 0 -0.4318 270)
			(size 0.127 0.127)
			(layers "F.Cu" "F.Mask" "F.Paste")
			(net "P3V3")
			(options
				(clearance outline)
				(anchor circle)
			)
			(primitives
				(gr_poly
					(pts
						(arc
							(start -0.2032 -0.2794)
							(mid -0.239121 -0.264521)
							(end -0.254 -0.2286)
						)
						(arc
							(start -0.254 0.2286)
							(mid -0.239121 0.264521)
							(end -0.2032 0.2794)
						)
						(arc
							(start 0.2032 0.2794)
							(mid 0.239121 0.264521)
							(end 0.254 0.2286)
						)
						(arc
							(start 0.254 -0.2286)
							(mid 0.239121 -0.264521)
							(end 0.2032 -0.2794)
						)
					)
					(width 0)
					(fill yes)
				)
			)
		)
		(pad "2" smd custom
			(at 0 0.4318 270)
			(size 0.127 0.127)
			(layers "F.Cu" "F.Mask" "F.Paste")
			(net "SMBUS_PECI_CLK")
			(options
				(clearance outline)
				(anchor circle)
			)
			(primitives
				(gr_poly
					(pts
						(arc
							(start -0.2032 -0.2794)
							(mid -0.239121 -0.264521)
							(end -0.254 -0.2286)
						)
						(arc
							(start -0.254 0.2286)
							(mid -0.239121 0.264521)
							(end -0.2032 0.2794)
						)
						(arc
							(start 0.2032 0.2794)
							(mid 0.239121 0.264521)
							(end 0.254 0.2286)
						)
						(arc
							(start 0.254 -0.2286)
							(mid 0.239121 -0.264521)
							(end 0.2032 -0.2794)
						)
					)
					(width 0)
					(fill yes)
				)
			)
		)
	)
	(footprint ""
		(layer "F.Cu")
		(at 56.896 -51.308 -90)
		(property "Reference" "PU11"
			(at 0 0 270)
			(layer "F.SilkS")
			(hide yes)
			(effects
				(font
					(size 1.27 1.27)
				)
			)
		)
		(property "Value" "EP53F8QI-T-GP"
			(at 2.827274 -2.223262 270)
			(unlocked yes)
			(layer "F.Fab")
			(hide yes)
			(effects
				(font
					(size 1.016 1.016)
					(thickness 0.1524)
				)
			)
		)
		(property "Device Type" "QFN16G3H46"
			(at 2.827274 -3.747262 270)
			(unlocked yes)
			(layer "F.Fab")
			(hide yes)
			(effects
				(font
					(size 1.016 1.016)
					(thickness 0.1524)
				)
			)
		)
		(duplicate_pad_numbers_are_jumpers no)
		(fp_poly
			(pts
				(xy 1.565656 -2.195576) (xy 1.252728 -1.882648) (xy 0.9398 -2.195576)
			)
			(stroke
				(width 0)
				(type default)
			)
			(fill yes)
			(layer "F.SilkS")
		)
		(fp_rect
			(start -1.8796 1.8796)
			(end 1.8796 -1.8796)
			(stroke
				(width 0)
				(type default)
			)
			(fill no)
			(layer "F.CrtYd")
		)
		(fp_rect
			(start -1.8796 1.8796)
			(end 1.8796 -1.8796)
			(stroke
				(width 0)
				(type default)
			)
			(fill no)
			(layer "F.Fab")
		)
		(pad "1" smd rect
			(at 1.249934 -1.32207 270)
			(size 0.3048 0.8636)
			(layers "F.Cu" "F.Mask" "F.Paste")
			(net "Net_645")
		)
		(pad "2" smd rect
			(at 0.750062 -1.32207 270)
			(size 0.3048 0.8636)
			(layers "F.Cu" "F.Mask" "F.Paste")
			(net "GND")
		)
		(pad "3" smd rect
			(at 0.249936 -1.32207 270)
			(size 0.3048 0.8636)
			(layers "F.Cu" "F.Mask" "F.Paste")
			(net "GND")
		)
		(pad "4" smd rect
			(at -0.249936 -1.32207 270)
			(size 0.3048 0.8636)
			(layers "F.Cu" "F.Mask" "F.Paste")
			(net "VR_AVIN_P1V0_STBY")
		)
		(pad "5" smd rect
			(at -0.750062 -1.32207 270)
			(size 0.3048 0.8636)
			(layers "F.Cu" "F.Mask" "F.Paste")
			(net "VR_FB_P1V0_STBY")
		)
		(pad "6" smd rect
			(at -1.249934 -1.32207 270)
			(size 0.3048 0.8636)
			(layers "F.Cu" "F.Mask" "F.Paste")
			(net "Net_648")
		)
		(pad "7" smd rect
			(at -1.32207 -0.249936 270)
			(size 0.8636 0.3048)
			(layers "F.Cu" "F.Mask" "F.Paste")
			(net "P1V0_STBY_VOUT")
		)
		(pad "8" smd rect
			(at -1.32207 0.249936 270)
			(size 0.8636 0.3048)
			(layers "F.Cu" "F.Mask" "F.Paste")
			(net "P1V0_STBY_VOUT")
		)
		(pad "9" smd rect
			(at -1.249934 1.32207 270)
			(size 0.3048 0.8636)
			(layers "F.Cu" "F.Mask" "F.Paste")
			(net "AGND_P1V0_STBY")
		)
		(pad "10" smd rect
			(at -0.750062 1.32207 270)
			(size 0.3048 0.8636)
			(layers "F.Cu" "F.Mask" "F.Paste")
			(net "VR_AVIN_P1V0_STBY")
		)
		(pad "11" smd rect
			(at -0.249936 1.32207 270)
			(size 0.3048 0.8636)
			(layers "F.Cu" "F.Mask" "F.Paste")
			(net "P1V0_STBY_PG")
		)
		(pad "12" smd rect
			(at 0.249936 1.32207 270)
			(size 0.3048 0.8636)
			(layers "F.Cu" "F.Mask" "F.Paste")
			(net "VR_EN_P1V0_STBY")
		)
		(pad "13" smd rect
			(at 0.750062 1.32207 270)
			(size 0.3048 0.8636)
			(layers "F.Cu" "F.Mask" "F.Paste")
			(net "VR_PVIN_P1V0_STBY")
		)
		(pad "14" smd rect
			(at 1.249934 1.32207 270)
			(size 0.3048 0.8636)
			(layers "F.Cu" "F.Mask" "F.Paste")
			(net "VR_PVIN_P1V0_STBY")
		)
		(pad "15" smd rect
			(at 1.32207 0.249936 270)
			(size 0.8636 0.3048)
			(layers "F.Cu" "F.Mask" "F.Paste")
			(net "Net_646")
		)
		(pad "16" smd rect
			(at 1.32207 -0.249936 270)
			(size 0.8636 0.3048)
			(layers "F.Cu" "F.Mask" "F.Paste")
			(net "Net_647")
		)
	)
	(footprint ""
		(layer "F.Cu")
		(at 145.923 -18.796)
		(property "Reference" "TP11"
			(at 0 0 0)
			(layer "F.SilkS")
			(hide yes)
			(effects
				(font
					(size 1.27 1.27)
				)
			)
		)
		(property "Value" "TPAD28-1-GP-U"
			(at 0.0508 -1.9304 0)
			(unlocked yes)
			(layer "F.Fab")
			(hide yes)
			(effects
				(font
					(size 1.016 1.016)
					(thickness 0.1524)
				)
			)
		)
		(property "Device Type" "TPAD28-1-U"
			(at 0.0508 -3.4544 0)
			(unlocked yes)
			(layer "F.Fab")
			(hide yes)
			(effects
				(font
					(size 1.016 1.016)
					(thickness 0.1524)
				)
			)
		)
		(duplicate_pad_numbers_are_jumpers no)
		(fp_poly
			(pts
				(arc
					(start 0.3556 0)
					(mid -0.3556 0)
					(end 0.3556 0)
				)
			)
			(stroke
				(width 0)
				(type default)
			)
			(fill no)
			(layer "F.CrtYd")
		)
		(fp_poly
			(pts
				(arc
					(start 0.9525 0)
					(mid -0.9525 0)
					(end 0.9525 0)
				)
			)
			(stroke
				(width 0)
				(type default)
			)
			(fill no)
			(layer "F.Fab")
		)
		(pad "1" smd circle
			(at 0 0)
			(size 0.7112 0.7112)
			(layers "F.Cu" "F.Mask" "F.Paste")
			(net "TP_FPGA_P100")
		)
	)
)
